G04*
G04 #@! TF.GenerationSoftware,Altium Limited,Altium Designer,23.7.1 (13)*
G04*
G04 Layer_Color=32896*
%FSLAX25Y25*%
%MOIN*%
G70*
G04*
G04 #@! TF.SameCoordinates,AF00DCEB-AC48-4C7C-91EA-99F42E284231*
G04*
G04*
G04 #@! TF.FilePolarity,Positive*
G04*
G01*
G75*
M02*
